FILE_TYPE = MACRO_DRAWING;
SET COLOR_WIRE YELLOW;
SET COLOR_PROP ORANGE;
SET COLOR_DOT WHITE;
SET COLOR_ARC YELLOW;
SET COLOR_BODY GREEN;
SET COLOR_NOTE PURPLE;
SET PROP_DISPLAY VALUE;
SET PAGE_NUMBER P135;
FORCEADD Q_CAP..1
R 2
(750 650);
FORCEPROP 1 LAST PART_NUMBER CH4104K1B00
J 2
(700 500);
DISPLAY 0.510638 (700 500);
DISPLAY INVISIBLE (700 500);
FORCEPROP 1 LAST VOLTAGE 25V
J 2
(700 650);
DISPLAY 0.510638 (700 650);
FORCEPROP 1 LAST TOLERANCE 10%
J 2
(700 600);
DISPLAY 0.510638 (700 600);
FORCEPROP 1 LAST VALUE 0.1UF
J 2
(700 700);
DISPLAY 0.510638 (700 700);
FORCEPROP 1 LAST MATERIAL X7R
J 2
(700 550);
DISPLAY 0.510638 (700 550);
FORCEPROP 1 LAST PACK_TYPE 0402
J 2
(700 450);
DISPLAY 0.510638 (700 450);
FORCEPROP 1 LAST $LOCATION C543
J 2
(700 750);
DISPLAY 0.978723 (700 750);
FORCEPROP 1 LASTPIN (750 750) $PN 1
J 2
(740 730);
DISPLAY 0.787234 (740 730);
FORCEPROP 1 LASTPIN (750 550) $PN 2
J 2
(740 530);
DISPLAY 0.787234 (740 530);
FORCEPROP 2 LAST CDS_LIB pure_quanta
J 0
(750 650);
PAINT MONO (750 650);
DISPLAY INVISIBLE (750 650);
FORCEPROP 1 LAST PATH I100
J 2
(700 800);
DISPLAY 0.978723 (700 800);
PAINT WHITE (700 800);
DISPLAY INVISIBLE (700 800);
FORCEPROP 2 LAST CDS_LOCATION C543
J 0
(700 850);
DISPLAY 1.021277 (700 850);
DISPLAY INVISIBLE (700 850);
FORCEPROP 2 LAST $SEC 1
J 0
(700 850);
DISPLAY 0.680851 (700 850);
PAINT MONO (700 850);
DISPLAY INVISIBLE (700 850);
FORCEPROP 2 LAST CDS_SEC 1
J 0
(700 850);
DISPLAY 1.021277 (700 850);
DISPLAY INVISIBLE (700 850);
FORCEADD UNIVERSAL_GND..1
(900 -200);
FORCEPROP 3 LASTPIN (900 -150) SIG_NAME GND\g
J 0
(910 -140);
DISPLAY 0.659574 (910 -140);
PAINT MONO (910 -140);
DISPLAY INVISIBLE (910 -140);
FORCEPROP 2 LAST CDS_LIB logical_power
J 0
(900 -200);
PAINT MONO (900 -200);
DISPLAY INVISIBLE (900 -200);
FORCEPROP 1 LAST HDL_POWER GND
J 1
(925 -275);
DISPLAY 0.872340 (925 -275);
PAINT GREEN (925 -275);
DISPLAY INVISIBLE (925 -275);
FORCEPROP 1 LAST PATH I103
J 0
(975 -200);
DISPLAY 0.872340 (975 -200);
PAINT AQUA (975 -200);
DISPLAY INVISIBLE (975 -200);
FORCEADD Q_RES..1
(-750 250);
FORCEPROP 1 LAST PART_NUMBER CS00002JB13
J 0
(-625 275);
DISPLAY 0.319149 (-625 275);
DISPLAY INVISIBLE (-625 275);
FORCEPROP 1 LAST WATTAGE 1/16W
J 2
(-450 300);
DISPLAY 0.319149 (-450 300);
FORCEPROP 1 LAST MATERIAL CHIP
J 0
(-625 300);
DISPLAY 0.319149 (-625 300);
FORCEPROP 1 LAST PACK_TYPE 0402LF
J 0
(-475 250);
DISPLAY 0.510638 (-475 250);
FORCEPROP 1 LAST TOLERANCE 5%
J 0
(-575 250);
DISPLAY 0.510638 (-575 250);
FORCEPROP 1 LAST VALUE 0
J 2
(-600 250);
DISPLAY 0.510638 (-600 250);
FORCEPROP 1 LAST $LOCATION R737
J 0
(-950 250);
DISPLAY 0.638298 (-950 250);
FORCEPROP 1 LASTPIN (-850 250) $PN 1
J 0
(-838 262);
DISPLAY 0.787234 (-838 262);
FORCEPROP 1 LASTPIN (-650 250) $PN 2
J 0
(-688 262);
DISPLAY 0.787234 (-688 262);
FORCEPROP 2 LAST CDS_LIB pure_quanta
J 0
(-750 250);
PAINT MONO (-750 250);
DISPLAY INVISIBLE (-750 250);
FORCEPROP 1 LAST PATH I106
J 0
(-800 400);
DISPLAY 0.978723 (-800 400);
PAINT WHITE (-800 400);
DISPLAY INVISIBLE (-800 400);
FORCEPROP 2 LAST CDS_LOCATION R737
J 0
(-800 450);
DISPLAY 1.021277 (-800 450);
DISPLAY INVISIBLE (-800 450);
FORCEPROP 2 LAST $SEC 1
J 0
(-800 450);
DISPLAY 0.680851 (-800 450);
PAINT MONO (-800 450);
DISPLAY INVISIBLE (-800 450);
FORCEPROP 2 LAST CDS_SEC 1
J 0
(-800 450);
DISPLAY 1.021277 (-800 450);
DISPLAY INVISIBLE (-800 450);
FORCEADD Q_RES..2
(-50 500);
FORCEPROP 1 LAST PART_NUMBER CS31002FB08
J 0
(-10 325);
DISPLAY 0.510638 (-10 325);
DISPLAY INVISIBLE (-10 325);
FORCEPROP 1 LAST VALUE 10K
J 0
(-5 575);
DISPLAY 0.638298 (-5 575);
FORCEPROP 1 LAST TOLERANCE 1%
J 0
(-5 525);
DISPLAY 0.638298 (-5 525);
FORCEPROP 1 LAST WATTAGE 1/16W
J 0
(-10 475);
DISPLAY 0.638298 (-10 475);
FORCEPROP 1 LAST PACK_TYPE 0402LF
J 0
(-10 375);
DISPLAY 0.638298 (-10 375);
FORCEPROP 1 LAST MATERIAL CHIP
J 0
(-10 425);
DISPLAY 0.638298 (-10 425);
FORCEPROP 1 LAST $LOCATION R740
J 0
(-5 625);
DISPLAY 0.978723 (-5 625);
FORCEPROP 1 LASTPIN (-50 600) $PN 1
J 0
(-45 562);
DISPLAY 0.787234 (-45 562);
FORCEPROP 1 LASTPIN (-50 400) $PN 2
J 0
(-45 410);
DISPLAY 0.787234 (-45 410);
FORCEPROP 2 LAST CDS_LIB pure_quanta
J 0
(-50 500);
PAINT MONO (-50 500);
DISPLAY INVISIBLE (-50 500);
FORCEPROP 1 LAST PATH I107
J 0
(0 675);
DISPLAY 0.978723 (0 675);
PAINT WHITE (0 675);
DISPLAY INVISIBLE (0 675);
FORCEPROP 2 LAST CDS_LOCATION R740
J 0
(0 725);
DISPLAY 1.021277 (0 725);
DISPLAY INVISIBLE (0 725);
FORCEPROP 2 LAST $SEC 1
J 0
(0 725);
DISPLAY 0.680851 (0 725);
PAINT MONO (0 725);
DISPLAY INVISIBLE (0 725);
FORCEPROP 2 LAST CDS_SEC 1
J 0
(0 725);
DISPLAY 1.021277 (0 725);
DISPLAY INVISIBLE (0 725);
FORCEADD UNIVERSAL_POWER..1
(-300 850);
FORCEPROP 3 LASTPIN (-300 800) SIG_NAME P3V3_AUX\g
J 0
(-290 810);
DISPLAY 0.659574 (-290 810);
PAINT MONO (-290 810);
DISPLAY INVISIBLE (-290 810);
FORCEPROP 1 LAST HDL_POWER P3V3_AUX
J 1
(-300 900);
DISPLAY 0.872340 (-300 900);
PAINT GREEN (-300 900);
FORCEPROP 2 LAST CDS_LIB logical_power
J 0
(-300 850);
PAINT MONO (-300 850);
DISPLAY INVISIBLE (-300 850);
FORCEPROP 1 LAST PATH I108
J 0
(-250 875);
DISPLAY 0.872340 (-250 875);
PAINT AQUA (-250 875);
DISPLAY INVISIBLE (-250 875);
FORCEADD Q_RES..2
(-300 500);
FORCEPROP 1 LAST PART_NUMBER CS31002FB08
J 0
(-260 375);
DISPLAY 0.638298 (-260 375);
DISPLAY INVISIBLE (-260 375);
FORCEPROP 1 LAST PACK_TYPE 0402LF
J 0
(-260 375);
DISPLAY 0.638298 (-260 375);
FORCEPROP 1 LAST VALUE 10K
J 0
(-255 575);
DISPLAY 0.638298 (-255 575);
FORCEPROP 1 LAST WATTAGE 1/16W
J 0
(-260 475);
DISPLAY 0.638298 (-260 475);
FORCEPROP 1 LAST MATERIAL CHIP
J 0
(-260 425);
DISPLAY 0.638298 (-260 425);
FORCEPROP 1 LAST TOLERANCE 1%
J 0
(-255 525);
DISPLAY 0.638298 (-255 525);
FORCEPROP 1 LAST $LOCATION R739
J 0
(-255 625);
DISPLAY 0.978723 (-255 625);
FORCEPROP 1 LASTPIN (-300 600) $PN 1
J 0
(-295 562);
DISPLAY 0.787234 (-295 562);
FORCEPROP 1 LASTPIN (-300 400) $PN 2
J 0
(-295 410);
DISPLAY 0.787234 (-295 410);
FORCEPROP 2 LAST CDS_LIB pure_quanta
J 0
(-300 500);
PAINT MONO (-300 500);
DISPLAY INVISIBLE (-300 500);
FORCEPROP 1 LAST PATH I109
J 0
(-250 675);
DISPLAY 0.978723 (-250 675);
PAINT WHITE (-250 675);
DISPLAY INVISIBLE (-250 675);
FORCEPROP 2 LAST CDS_LOCATION R739
J 0
(-250 725);
DISPLAY 1.021277 (-250 725);
DISPLAY INVISIBLE (-250 725);
FORCEPROP 2 LAST $SEC 1
J 0
(-250 725);
DISPLAY 0.680851 (-250 725);
PAINT MONO (-250 725);
DISPLAY INVISIBLE (-250 725);
FORCEPROP 2 LAST CDS_SEC 1
J 0
(-250 725);
DISPLAY 1.021277 (-250 725);
DISPLAY INVISIBLE (-250 725);
FORCEADD Q_RES..1
(-750 150);
FORCEPROP 1 LAST PART_NUMBER CS00002JB13
J 0
(-625 175);
DISPLAY 0.319149 (-625 175);
DISPLAY INVISIBLE (-625 175);
FORCEPROP 1 LAST WATTAGE 1/16W
J 2
(-450 200);
DISPLAY 0.319149 (-450 200);
FORCEPROP 1 LAST TOLERANCE 5%
J 0
(-575 150);
DISPLAY 0.510638 (-575 150);
FORCEPROP 1 LAST MATERIAL CHIP
J 0
(-625 200);
DISPLAY 0.319149 (-625 200);
FORCEPROP 1 LAST VALUE 0
J 2
(-600 150);
DISPLAY 0.510638 (-600 150);
FORCEPROP 1 LAST PACK_TYPE 0402LF
J 0
(-475 150);
DISPLAY 0.510638 (-475 150);
FORCEPROP 1 LAST $LOCATION R738
J 0
(-950 150);
DISPLAY 0.638298 (-950 150);
FORCEPROP 1 LASTPIN (-850 150) $PN 1
J 0
(-838 162);
DISPLAY 0.787234 (-838 162);
FORCEPROP 1 LASTPIN (-650 150) $PN 2
J 0
(-688 162);
DISPLAY 0.787234 (-688 162);
FORCEPROP 2 LAST CDS_LIB pure_quanta
J 0
(-750 150);
PAINT MONO (-750 150);
DISPLAY INVISIBLE (-750 150);
FORCEPROP 1 LAST PATH I110
J 0
(-800 300);
DISPLAY 0.978723 (-800 300);
PAINT WHITE (-800 300);
DISPLAY INVISIBLE (-800 300);
FORCEPROP 2 LAST CDS_LOCATION R738
J 0
(-800 350);
DISPLAY 1.021277 (-800 350);
DISPLAY INVISIBLE (-800 350);
FORCEPROP 2 LAST $SEC 1
J 0
(-800 350);
DISPLAY 0.680851 (-800 350);
PAINT MONO (-800 350);
DISPLAY INVISIBLE (-800 350);
FORCEPROP 2 LAST CDS_SEC 1
J 0
(-800 350);
DISPLAY 1.021277 (-800 350);
DISPLAY INVISIBLE (-800 350);
FORCEADD OFFPAGE..1
(-1875 250);
FORCEPROP 2 LAST $XR1 222 
J 0
(-2246 250);
DISPLAY 0.638298 (-2246 250);
PAINT MONO (-2246 250);
FORCEPROP 2 LAST $XR0 45 
J 0
(-2126 250);
DISPLAY 0.638298 (-2126 250);
PAINT MONO (-2126 250);
FORCEPROP 2 LAST CDS_LIB standard
J 0
(-1875 250);
PAINT MONO (-1875 250);
DISPLAY INVISIBLE (-1875 250);
FORCEPROP 1 LAST OFFPAGE TRUE
J 0
(-1550 125);
DISPLAY 0.872340 (-1550 125);
PAINT GREEN (-1550 125);
DISPLAY INVISIBLE (-1550 125);
FORCEPROP 1 LAST COMMENT_BODY TRUE
J 0
(-1750 150);
DISPLAY 0.872340 (-1750 150);
PAINT GREEN (-1750 150);
DISPLAY INVISIBLE (-1750 150);
FORCEPROP 2 LAST PATH I111
J 0
(-1825 325);
DISPLAY 1.021277 (-1825 325);
DISPLAY INVISIBLE (-1825 325);
FORCEADD OFFPAGE..1
(-1875 150);
FORCEPROP 2 LAST $XR1 222 
J 0
(-2246 150);
DISPLAY 0.638298 (-2246 150);
PAINT MONO (-2246 150);
FORCEPROP 2 LAST $XR0 14 
J 0
(-2126 150);
DISPLAY 0.638298 (-2126 150);
PAINT MONO (-2126 150);
FORCEPROP 2 LAST CDS_LIB standard
J 0
(-1875 150);
PAINT MONO (-1875 150);
DISPLAY INVISIBLE (-1875 150);
FORCEPROP 1 LAST OFFPAGE TRUE
J 0
(-1550 25);
DISPLAY 0.872340 (-1550 25);
PAINT GREEN (-1550 25);
DISPLAY INVISIBLE (-1550 25);
FORCEPROP 1 LAST COMMENT_BODY TRUE
J 0
(-1750 50);
DISPLAY 0.872340 (-1750 50);
PAINT GREEN (-1750 50);
DISPLAY INVISIBLE (-1750 50);
FORCEPROP 2 LAST PATH I112
J 0
(-1825 225);
DISPLAY 1.021277 (-1825 225);
DISPLAY INVISIBLE (-1825 225);
FORCEADD OFFPAGE..5
(-350 -100);
FORCEPROP 2 LAST $XR0 133 
J 0
(-635 -100);
DISPLAY 0.638298 (-635 -100);
PAINT MONO (-635 -100);
FORCEPROP 2 LAST CDS_LIB standard
J 0
(-350 -100);
PAINT MONO (-350 -100);
DISPLAY INVISIBLE (-350 -100);
FORCEPROP 1 LAST OFFPAGE TRUE
J 0
(-25 -225);
DISPLAY 0.872340 (-25 -225);
DISPLAY INVISIBLE (-25 -225);
FORCEPROP 1 LAST COMMENT_BODY TRUE
J 0
(-250 -175);
DISPLAY 0.872340 (-250 -175);
PAINT GREEN (-250 -175);
DISPLAY INVISIBLE (-250 -175);
FORCEPROP 2 LAST PATH I113
J 0
(-625 -50);
DISPLAY 1.021277 (-625 -50);
DISPLAY INVISIBLE (-625 -50);
FORCEADD OFFPAGE..5
(-350 0);
FORCEPROP 2 LAST $XR0 133 
J 0
(-635 0);
DISPLAY 0.638298 (-635 0);
PAINT MONO (-635 0);
FORCEPROP 2 LAST CDS_LIB standard
J 0
(-350 0);
PAINT MONO (-350 0);
DISPLAY INVISIBLE (-350 0);
FORCEPROP 1 LAST OFFPAGE TRUE
J 0
(-25 -125);
DISPLAY 0.872340 (-25 -125);
DISPLAY INVISIBLE (-25 -125);
FORCEPROP 1 LAST COMMENT_BODY TRUE
J 0
(-250 -75);
DISPLAY 0.872340 (-250 -75);
PAINT GREEN (-250 -75);
DISPLAY INVISIBLE (-250 -75);
FORCEPROP 2 LAST PATH I114
J 0
(-625 50);
DISPLAY 1.021277 (-625 50);
DISPLAY INVISIBLE (-625 50);
FORCEADD 74LVC1G66GV..1
R 2
(3375 250);
FORCEPROP 1 LAST PART_NUMBER AL001G66000
J 2
(3530 494);
DISPLAY 0.723404 (3530 494);
PAINT GREEN (3530 494);
DISPLAY INVISIBLE (3530 494);
FORCEPROP 2 LAST VALUE 74LVC1G66GV
J 2
(3525 625);
DISPLAY 1.021277 (3525 625);
FORCEPROP 2 LAST PART_TYPE SMLF
J 2
(3525 675);
DISPLAY 1.021277 (3525 675);
FORCEPROP 1 LAST MATERIAL IC
J 2
(3530 405);
DISPLAY 0.723404 (3530 405);
PAINT GREEN (3530 405);
FORCEPROP 1 LAST LOCATION U16
J 2
(3525 575);
DISPLAY 0.723404 (3525 575);
PAINT GREEN (3525 575);
FORCEPROP 2 LASTPIN (3075 200) $PN 4
J 2
(3065 210);
DISPLAY 0.680851 (3065 210);
PAINT MONO (3065 210);
FORCEPROP 2 LASTPIN (3675 150) $PN 3
J 0
(3685 160);
DISPLAY 0.680851 (3685 160);
PAINT MONO (3685 160);
FORCEPROP 2 LASTPIN (3075 350) $PN 5
J 2
(3065 360);
DISPLAY 0.680851 (3065 360);
PAINT MONO (3065 360);
FORCEPROP 2 LASTPIN (3675 350) $PN 1
J 0
(3685 360);
DISPLAY 0.680851 (3685 360);
PAINT MONO (3685 360);
FORCEPROP 2 LASTPIN (3675 250) $PN 2
J 0
(3685 260);
DISPLAY 0.680851 (3685 260);
PAINT MONO (3685 260);
FORCEPROP 2 LAST SEC_TYPE 
J 0
(3525 725);
DISPLAY 1.021277 (3525 725);
DISPLAY INVISIBLE (3525 725);
FORCEPROP 1 LAST CDS_LMAN_SYM_OUTLINE -150,150,150,-150
J 2
(3375 250);
DISPLAY 0.468085 (3375 250);
PAINT GREEN (3375 250);
DISPLAY INVISIBLE (3375 250);
FORCEPROP 1 LAST PIN_NAMES_ROTATE True
J 2
(3375 250);
DISPLAY 0.489362 (3375 250);
PAINT GREEN (3375 250);
DISPLAY INVISIBLE (3375 250);
FORCEPROP 2 LAST CDS_LIB pure_quanta
J 2
(3375 250);
DISPLAY INVISIBLE (3375 250);
FORCEPROP 1 LAST PATH I115
J 2
(3225 100);
DISPLAY 0.723404 (3225 100);
PAINT GREEN (3225 100);
DISPLAY INVISIBLE (3225 100);
FORCEPROP 2 LAST SEC 1
J 0
(3525 725);
DISPLAY 0.680851 (3525 725);
PAINT MONO (3525 725);
DISPLAY INVISIBLE (3525 725);
FORCEADD OFFPAGE..1
(-1850 3450);
FORCEPROP 2 LAST $XR0 132 
J 0
(-2102 3450);
DISPLAY 0.638298 (-2102 3450);
PAINT MONO (-2102 3450);
FORCEPROP 2 LAST CDS_LIB standard
J 0
(-1850 3450);
PAINT MONO (-1850 3450);
DISPLAY INVISIBLE (-1850 3450);
FORCEPROP 1 LAST OFFPAGE TRUE
J 0
(-1525 3325);
DISPLAY 0.872340 (-1525 3325);
PAINT GREEN (-1525 3325);
DISPLAY INVISIBLE (-1525 3325);
FORCEPROP 1 LAST COMMENT_BODY TRUE
J 0
(-1725 3350);
DISPLAY 0.872340 (-1725 3350);
PAINT GREEN (-1725 3350);
DISPLAY INVISIBLE (-1725 3350);
FORCEPROP 2 LAST PATH I23
J 0
(-1800 3525);
DISPLAY 1.021277 (-1800 3525);
DISPLAY INVISIBLE (-1800 3525);
FORCEADD UNIVERSAL_GND..1
(-175 3050);
FORCEPROP 3 LASTPIN (-175 3100) SIG_NAME GND\g
J 0
(-165 3110);
DISPLAY 0.659574 (-165 3110);
PAINT MONO (-165 3110);
DISPLAY INVISIBLE (-165 3110);
FORCEPROP 2 LAST CDS_LIB logical_power
J 0
(-175 3050);
PAINT MONO (-175 3050);
DISPLAY INVISIBLE (-175 3050);
FORCEPROP 1 LAST HDL_POWER GND
J 1
(-150 2975);
DISPLAY 0.872340 (-150 2975);
PAINT GREEN (-150 2975);
DISPLAY INVISIBLE (-150 2975);
FORCEPROP 1 LAST PATH I27
J 0
(-100 3050);
DISPLAY 0.872340 (-100 3050);
PAINT AQUA (-100 3050);
DISPLAY INVISIBLE (-100 3050);
FORCEADD NC7SB3157..1
R 2
(-600 3550);
FORCEPROP 1 LAST PART_NUMBER ALSB3157000
J 2
(-473 3710);
DISPLAY 0.723404 (-473 3710);
PAINT GREEN (-473 3710);
DISPLAY INVISIBLE (-473 3710);
FORCEPROP 1 LAST MATERIAL IC
J 2
(-473 3630);
DISPLAY 0.723404 (-473 3630);
PAINT GREEN (-473 3630);
FORCEPROP 1 LAST VALUE NC7SB3157P6X
J 2
(-473 3870);
DISPLAY 0.723404 (-473 3870);
PAINT GREEN (-473 3870);
FORCEPROP 2 LAST MANUF_PN NC7SB3157P6X
J 2
(-475 3975);
DISPLAY 0.808511 (-475 3975);
FORCEPROP 2 LAST PATH I58
J 2
(-475 3925);
DISPLAY 0.808511 (-475 3925);
FORCEPROP 1 LAST $LOCATION U21
J 2
(-473 3790);
DISPLAY 0.723404 (-473 3790);
PAINT GREEN (-473 3790);
FORCEPROP 1 LASTPIN (-900 3450) $PN 4
J 2
(-790 3453);
DISPLAY 0.659574 (-790 3453);
PAINT GREEN (-790 3453);
FORCEPROP 1 LASTPIN (-300 3450) $PN 3
J 0
(-410 3453);
DISPLAY 0.659574 (-410 3453);
PAINT GREEN (-410 3453);
FORCEPROP 1 LASTPIN (-300 3550) $PN 1
J 0
(-410 3553);
DISPLAY 0.659574 (-410 3553);
PAINT GREEN (-410 3553);
FORCEPROP 1 LASTPIN (-300 3500) $PN 2
J 0
(-410 3503);
DISPLAY 0.659574 (-410 3503);
PAINT GREEN (-410 3503);
FORCEPROP 1 LASTPIN (-900 3550) $PN 6
J 2
(-790 3553);
DISPLAY 0.659574 (-790 3553);
PAINT GREEN (-790 3553);
FORCEPROP 1 LASTPIN (-900 3500) $PN 5
J 2
(-790 3503);
DISPLAY 0.659574 (-790 3503);
PAINT GREEN (-790 3503);
FORCEPROP 1 LAST PACK_TYPE SMLF
J 2
(-600 3300);
DISPLAY 0.723404 (-600 3300);
PAINT GREEN (-600 3300);
DISPLAY INVISIBLE (-600 3300);
FORCEPROP 2 LAST CDS_LIB pure_quanta
J 2
(-600 3550);
PAINT MONO (-600 3550);
DISPLAY INVISIBLE (-600 3550);
FORCEPROP 1 LAST CDS_LMAN_SYM_OUTLINE -150,50,150,-150
J 2
(-600 3550);
DISPLAY 0.468085 (-600 3550);
PAINT GREEN (-600 3550);
DISPLAY INVISIBLE (-600 3550);
FORCEPROP 2 LAST CDS_LOCATION U21
J 0
(-475 4025);
DISPLAY 1.021277 (-475 4025);
DISPLAY INVISIBLE (-475 4025);
FORCEPROP 2 LAST $SEC 1
J 0
(-475 4025);
DISPLAY 0.680851 (-475 4025);
PAINT MONO (-475 4025);
DISPLAY INVISIBLE (-475 4025);
FORCEPROP 2 LAST CDS_SEC 1
J 0
(-475 4025);
DISPLAY 1.021277 (-475 4025);
DISPLAY INVISIBLE (-475 4025);
FORCEADD OFFPAGE..1
(-1850 3550);
FORCEPROP 2 LAST $XR0 133 
J 0
(-2102 3550);
DISPLAY 0.638298 (-2102 3550);
PAINT MONO (-2102 3550);
FORCEPROP 2 LAST CDS_LIB standard
J 0
(-1850 3550);
PAINT MONO (-1850 3550);
DISPLAY INVISIBLE (-1850 3550);
FORCEPROP 1 LAST OFFPAGE TRUE
J 0
(-1525 3425);
DISPLAY 0.872340 (-1525 3425);
PAINT GREEN (-1525 3425);
DISPLAY INVISIBLE (-1525 3425);
FORCEPROP 1 LAST COMMENT_BODY TRUE
J 0
(-1725 3450);
DISPLAY 0.872340 (-1725 3450);
PAINT GREEN (-1725 3450);
DISPLAY INVISIBLE (-1725 3450);
FORCEPROP 2 LAST PATH I59
J 0
(-1800 3625);
DISPLAY 1.021277 (-1800 3625);
DISPLAY INVISIBLE (-1800 3625);
FORCEADD UNIVERSAL_POWER..1
(-1000 4225);
FORCEPROP 3 LASTPIN (-1000 4175) SIG_NAME P3V3_AUX\g
J 0
(-990 4185);
DISPLAY 0.659574 (-990 4185);
PAINT MONO (-990 4185);
DISPLAY INVISIBLE (-990 4185);
FORCEPROP 1 LAST HDL_POWER P3V3_AUX
J 1
(-1000 4275);
DISPLAY 0.872340 (-1000 4275);
PAINT GREEN (-1000 4275);
FORCEPROP 2 LAST CDS_LIB logical_power
J 0
(-1000 4225);
PAINT MONO (-1000 4225);
DISPLAY INVISIBLE (-1000 4225);
FORCEPROP 1 LAST PATH I60
J 0
(-950 4250);
DISPLAY 0.872340 (-950 4250);
PAINT AQUA (-950 4250);
DISPLAY INVISIBLE (-950 4250);
FORCEADD Q_CAP..1
R 2
(-1150 3950);
FORCEPROP 1 LAST PART_NUMBER CH5104KEB02
J 2
(-1200 3800);
DISPLAY 0.510638 (-1200 3800);
DISPLAY INVISIBLE (-1200 3800);
FORCEPROP 1 LAST VALUE 1UF
J 2
(-1200 4000);
DISPLAY 0.510638 (-1200 4000);
FORCEPROP 1 LAST VOLTAGE 25V
J 2
(-1200 3950);
DISPLAY 0.510638 (-1200 3950);
FORCEPROP 1 LAST TOLERANCE 10%
J 2
(-1200 3900);
DISPLAY 0.510638 (-1200 3900);
FORCEPROP 1 LAST MATERIAL X6S
J 2
(-1200 3850);
DISPLAY 0.510638 (-1200 3850);
FORCEPROP 1 LAST PACK_TYPE C0402
J 2
(-1200 3750);
DISPLAY 0.510638 (-1200 3750);
FORCEPROP 1 LAST $LOCATION C541
J 2
(-1200 4050);
DISPLAY 0.978723 (-1200 4050);
FORCEPROP 1 LASTPIN (-1150 4050) $PN 1
J 2
(-1160 4030);
DISPLAY 0.787234 (-1160 4030);
FORCEPROP 1 LASTPIN (-1150 3850) $PN 2
J 2
(-1160 3830);
DISPLAY 0.787234 (-1160 3830);
FORCEPROP 2 LAST CDS_LIB pure_quanta
J 2
(-1150 3950);
PAINT MONO (-1150 3950);
DISPLAY INVISIBLE (-1150 3950);
FORCEPROP 1 LAST PATH I61
J 2
(-1200 4100);
DISPLAY 0.978723 (-1200 4100);
PAINT WHITE (-1200 4100);
DISPLAY INVISIBLE (-1200 4100);
FORCEPROP 2 LAST CDS_LOCATION C541
J 0
(-1200 4150);
DISPLAY 1.021277 (-1200 4150);
DISPLAY INVISIBLE (-1200 4150);
FORCEPROP 2 LAST $SEC 1
J 0
(-1200 4150);
DISPLAY 0.680851 (-1200 4150);
PAINT MONO (-1200 4150);
DISPLAY INVISIBLE (-1200 4150);
FORCEPROP 2 LAST CDS_SEC 1
J 0
(-1200 4150);
DISPLAY 1.021277 (-1200 4150);
DISPLAY INVISIBLE (-1200 4150);
FORCEADD OFFPAGE..2
(1625 3450);
FORCEPROP 2 LAST $XR0 13 
J 0
(1814 3450);
DISPLAY 0.638298 (1814 3450);
PAINT MONO (1814 3450);
FORCEPROP 2 LAST CDS_LIB standard
J 0
(1625 3450);
PAINT MONO (1625 3450);
DISPLAY INVISIBLE (1625 3450);
FORCEPROP 1 LAST OFFPAGE TRUE
J 0
(1950 3325);
DISPLAY 0.872340 (1950 3325);
PAINT GREEN (1950 3325);
DISPLAY INVISIBLE (1950 3325);
FORCEPROP 1 LAST COMMENT_BODY TRUE
J 0
(1580 3355);
DISPLAY 0.872340 (1580 3355);
PAINT GREEN (1580 3355);
DISPLAY INVISIBLE (1580 3355);
FORCEPROP 2 LAST PATH I63
J 0
(1800 3525);
DISPLAY 1.021277 (1800 3525);
DISPLAY INVISIBLE (1800 3525);
FORCEADD OFFPAGE..2
(1625 3550);
FORCEPROP 2 LAST $XR1 44 
J 0
(1934 3550);
DISPLAY 0.638298 (1934 3550);
PAINT MONO (1934 3550);
FORCEPROP 2 LAST $XR0 133 
J 0
(1814 3550);
DISPLAY 0.638298 (1814 3550);
PAINT MONO (1814 3550);
FORCEPROP 2 LAST CDS_LIB standard
J 0
(1625 3550);
PAINT MONO (1625 3550);
DISPLAY INVISIBLE (1625 3550);
FORCEPROP 1 LAST OFFPAGE TRUE
J 0
(1950 3425);
DISPLAY 0.872340 (1950 3425);
PAINT GREEN (1950 3425);
DISPLAY INVISIBLE (1950 3425);
FORCEPROP 1 LAST COMMENT_BODY TRUE
J 0
(1580 3455);
DISPLAY 0.872340 (1580 3455);
PAINT GREEN (1580 3455);
DISPLAY INVISIBLE (1580 3455);
FORCEPROP 2 LAST PATH I64
J 0
(1800 3625);
DISPLAY 1.021277 (1800 3625);
DISPLAY INVISIBLE (1800 3625);
FORCEADD Q_RES..2
(1250 3800);
FORCEPROP 1 LAST PART_NUMBER CS11502FB07
J 0
(1290 3700);
DISPLAY 0.404255 (1290 3700);
DISPLAY INVISIBLE (1290 3700);
FORCEPROP 1 LAST VALUE 150
J 0
(1295 3900);
DISPLAY 0.510638 (1295 3900);
FORCEPROP 1 LAST TOLERANCE 1%
J 0
(1295 3850);
DISPLAY 0.510638 (1295 3850);
FORCEPROP 1 LAST WATTAGE 1/16W
J 0
(1290 3800);
DISPLAY 0.510638 (1290 3800);
FORCEPROP 1 LAST PACK_TYPE 0402LF
J 0
(1290 3650);
DISPLAY 0.510638 (1290 3650);
FORCEPROP 1 LAST MATERIAL CHIP
J 0
(1290 3750);
DISPLAY 0.510638 (1290 3750);
FORCEPROP 1 LAST $LOCATION R743
J 0
(1295 3950);
DISPLAY 0.978723 (1295 3950);
FORCEPROP 1 LASTPIN (1250 3900) $PN 1
J 0
(1255 3862);
DISPLAY 0.787234 (1255 3862);
FORCEPROP 1 LASTPIN (1250 3700) $PN 2
J 0
(1255 3710);
DISPLAY 0.787234 (1255 3710);
FORCEPROP 2 LAST CDS_LIB pure_quanta
J 0
(1250 3800);
PAINT MONO (1250 3800);
DISPLAY INVISIBLE (1250 3800);
FORCEPROP 1 LAST PATH I65
J 0
(1300 3975);
DISPLAY 0.978723 (1300 3975);
PAINT WHITE (1300 3975);
DISPLAY INVISIBLE (1300 3975);
FORCEPROP 2 LAST CDS_LOCATION R743
J 0
(1300 4025);
DISPLAY 1.021277 (1300 4025);
DISPLAY INVISIBLE (1300 4025);
FORCEPROP 2 LAST $SEC 1
J 0
(1300 4025);
DISPLAY 0.680851 (1300 4025);
PAINT MONO (1300 4025);
DISPLAY INVISIBLE (1300 4025);
FORCEPROP 2 LAST CDS_SEC 1
J 0
(1300 4025);
DISPLAY 1.021277 (1300 4025);
DISPLAY INVISIBLE (1300 4025);
FORCEADD Q_RES..2
(600 3800);
FORCEPROP 1 LAST PART_NUMBER CS11502FB07
J 0
(640 3700);
DISPLAY 0.404255 (640 3700);
DISPLAY INVISIBLE (640 3700);
FORCEPROP 1 LAST VALUE 150
J 0
(645 3900);
DISPLAY 0.510638 (645 3900);
FORCEPROP 1 LAST WATTAGE 1/16W
J 0
(640 3800);
DISPLAY 0.510638 (640 3800);
FORCEPROP 1 LAST PACK_TYPE 0402LF
J 0
(640 3650);
DISPLAY 0.510638 (640 3650);
FORCEPROP 1 LAST TOLERANCE 1%
J 0
(645 3850);
DISPLAY 0.510638 (645 3850);
FORCEPROP 1 LAST MATERIAL CHIP
J 0
(640 3750);
DISPLAY 0.510638 (640 3750);
FORCEPROP 1 LAST $LOCATION R741
J 0
(645 3950);
DISPLAY 0.978723 (645 3950);
FORCEPROP 1 LASTPIN (600 3900) $PN 1
J 0
(605 3862);
DISPLAY 0.787234 (605 3862);
FORCEPROP 1 LASTPIN (600 3700) $PN 2
J 0
(605 3710);
DISPLAY 0.787234 (605 3710);
FORCEPROP 2 LAST CDS_LIB pure_quanta
J 0
(600 3800);
PAINT MONO (600 3800);
DISPLAY INVISIBLE (600 3800);
FORCEPROP 1 LAST PATH I66
J 0
(650 3975);
DISPLAY 0.978723 (650 3975);
PAINT WHITE (650 3975);
DISPLAY INVISIBLE (650 3975);
FORCEPROP 2 LAST CDS_LOCATION R741
J 0
(650 4025);
DISPLAY 1.021277 (650 4025);
DISPLAY INVISIBLE (650 4025);
FORCEPROP 2 LAST $SEC 1
J 0
(650 4025);
DISPLAY 0.680851 (650 4025);
PAINT MONO (650 4025);
DISPLAY INVISIBLE (650 4025);
FORCEPROP 2 LAST CDS_SEC 1
J 0
(650 4025);
DISPLAY 1.021277 (650 4025);
DISPLAY INVISIBLE (650 4025);
FORCEADD UNIVERSAL_POWER..1
(600 4275);
FORCEPROP 3 LASTPIN (600 4225) SIG_NAME PVNN_TERM_CPU0\g
J 0
(610 4235);
DISPLAY 0.659574 (610 4235);
PAINT MONO (610 4235);
DISPLAY INVISIBLE (610 4235);
FORCEPROP 1 LAST HDL_POWER PVNN_TERM_CPU0
J 1
(600 4325);
DISPLAY 0.872340 (600 4325);
PAINT GREEN (600 4325);
FORCEPROP 2 LAST CDS_LIB logical_power
J 0
(600 4275);
PAINT MONO (600 4275);
DISPLAY INVISIBLE (600 4275);
FORCEPROP 1 LAST PATH I67
J 0
(650 4300);
DISPLAY 0.872340 (650 4300);
PAINT AQUA (650 4300);
DISPLAY INVISIBLE (650 4300);
FORCEADD UNIVERSAL_POWER..1
(1250 4275);
FORCEPROP 3 LASTPIN (1250 4225) SIG_NAME PVNN_TERM_CPU1\g
J 0
(1260 4235);
DISPLAY 0.659574 (1260 4235);
PAINT MONO (1260 4235);
DISPLAY INVISIBLE (1260 4235);
FORCEPROP 1 LAST HDL_POWER PVNN_TERM_CPU1
J 1
(1250 4325);
DISPLAY 0.872340 (1250 4325);
PAINT GREEN (1250 4325);
FORCEPROP 2 LAST CDS_LIB logical_power
J 0
(1250 4275);
PAINT MONO (1250 4275);
DISPLAY INVISIBLE (1250 4275);
FORCEPROP 1 LAST PATH I68
J 0
(1300 4300);
DISPLAY 0.872340 (1300 4300);
PAINT AQUA (1300 4300);
DISPLAY INVISIBLE (1300 4300);
FORCEADD UNIVERSAL_GND..1
(-1500 3650);
FORCEPROP 3 LASTPIN (-1500 3700) SIG_NAME GND\g
J 0
(-1490 3710);
DISPLAY 0.659574 (-1490 3710);
PAINT MONO (-1490 3710);
DISPLAY INVISIBLE (-1490 3710);
FORCEPROP 2 LAST CDS_LIB logical_power
J 0
(-1500 3650);
PAINT MONO (-1500 3650);
DISPLAY INVISIBLE (-1500 3650);
FORCEPROP 1 LAST HDL_POWER GND
J 1
(-1475 3575);
DISPLAY 0.872340 (-1475 3575);
PAINT GREEN (-1475 3575);
DISPLAY INVISIBLE (-1475 3575);
FORCEPROP 1 LAST PATH I69
J 0
(-1425 3650);
DISPLAY 0.872340 (-1425 3650);
PAINT AQUA (-1425 3650);
DISPLAY INVISIBLE (-1425 3650);
FORCEADD Q_CAP..1
R 2
(-1500 3950);
FORCEPROP 1 LAST PART_NUMBER CH4104K1B00
J 2
(-1550 3800);
DISPLAY 0.510638 (-1550 3800);
DISPLAY INVISIBLE (-1550 3800);
FORCEPROP 1 LAST TOLERANCE 10%
J 2
(-1550 3900);
DISPLAY 0.510638 (-1550 3900);
FORCEPROP 1 LAST PACK_TYPE 0402
J 2
(-1550 3750);
DISPLAY 0.510638 (-1550 3750);
FORCEPROP 1 LAST MATERIAL X7R
J 2
(-1550 3850);
DISPLAY 0.510638 (-1550 3850);
FORCEPROP 1 LAST VOLTAGE 25V
J 2
(-1550 3950);
DISPLAY 0.510638 (-1550 3950);
FORCEPROP 1 LAST VALUE 0.1UF
J 2
(-1550 4000);
DISPLAY 0.510638 (-1550 4000);
FORCEPROP 1 LAST $LOCATION C539
J 2
(-1550 4050);
DISPLAY 0.978723 (-1550 4050);
FORCEPROP 1 LASTPIN (-1500 4050) $PN 1
J 2
(-1510 4030);
DISPLAY 0.787234 (-1510 4030);
FORCEPROP 1 LASTPIN (-1500 3850) $PN 2
J 2
(-1510 3830);
DISPLAY 0.787234 (-1510 3830);
FORCEPROP 2 LAST CDS_LIB pure_quanta
J 2
(-1500 3950);
PAINT MONO (-1500 3950);
DISPLAY INVISIBLE (-1500 3950);
FORCEPROP 1 LAST PATH I70
J 2
(-1550 4100);
DISPLAY 0.978723 (-1550 4100);
PAINT WHITE (-1550 4100);
DISPLAY INVISIBLE (-1550 4100);
FORCEPROP 2 LAST CDS_LOCATION C539
J 0
(-1550 4150);
DISPLAY 1.021277 (-1550 4150);
DISPLAY INVISIBLE (-1550 4150);
FORCEPROP 2 LAST $SEC 1
J 0
(-1550 4150);
DISPLAY 0.680851 (-1550 4150);
PAINT MONO (-1550 4150);
DISPLAY INVISIBLE (-1550 4150);
FORCEPROP 2 LAST CDS_SEC 1
J 0
(-1550 4150);
DISPLAY 1.021277 (-1550 4150);
DISPLAY INVISIBLE (-1550 4150);
FORCEADD NC7SB3157..1
R 2
(-600 2000);
FORCEPROP 1 LAST PART_NUMBER ALSB3157000
J 2
(-473 2160);
DISPLAY 0.723404 (-473 2160);
PAINT GREEN (-473 2160);
DISPLAY INVISIBLE (-473 2160);
FORCEPROP 1 LAST MATERIAL IC
J 2
(-473 2080);
DISPLAY 0.723404 (-473 2080);
PAINT GREEN (-473 2080);
FORCEPROP 1 LAST VALUE NC7SB3157P6X
J 2
(-473 2320);
DISPLAY 0.723404 (-473 2320);
PAINT GREEN (-473 2320);
FORCEPROP 2 LAST MANUF_PN NC7SB3157P6X
J 2
(-475 2425);
DISPLAY 0.808511 (-475 2425);
FORCEPROP 1 LAST $LOCATION U22
J 2
(-473 2240);
DISPLAY 0.723404 (-473 2240);
PAINT GREEN (-473 2240);
FORCEPROP 1 LASTPIN (-900 1900) $PN 4
J 2
(-790 1903);
DISPLAY 0.659574 (-790 1903);
PAINT GREEN (-790 1903);
FORCEPROP 1 LASTPIN (-300 1900) $PN 3
J 0
(-410 1903);
DISPLAY 0.659574 (-410 1903);
PAINT GREEN (-410 1903);
FORCEPROP 1 LASTPIN (-300 2000) $PN 1
J 0
(-410 2003);
DISPLAY 0.659574 (-410 2003);
PAINT GREEN (-410 2003);
FORCEPROP 1 LASTPIN (-300 1950) $PN 2
J 0
(-410 1953);
DISPLAY 0.659574 (-410 1953);
PAINT GREEN (-410 1953);
FORCEPROP 1 LASTPIN (-900 2000) $PN 6
J 2
(-790 2003);
DISPLAY 0.659574 (-790 2003);
PAINT GREEN (-790 2003);
FORCEPROP 1 LASTPIN (-900 1950) $PN 5
J 2
(-790 1953);
DISPLAY 0.659574 (-790 1953);
PAINT GREEN (-790 1953);
FORCEPROP 1 LAST CDS_LMAN_SYM_OUTLINE -150,50,150,-150
J 2
(-600 2000);
DISPLAY 0.468085 (-600 2000);
PAINT GREEN (-600 2000);
DISPLAY INVISIBLE (-600 2000);
FORCEPROP 2 LAST CDS_LIB pure_quanta
J 2
(-600 2000);
PAINT MONO (-600 2000);
DISPLAY INVISIBLE (-600 2000);
FORCEPROP 1 LAST PACK_TYPE SMLF
J 2
(-600 1750);
DISPLAY 0.723404 (-600 1750);
PAINT GREEN (-600 1750);
DISPLAY INVISIBLE (-600 1750);
FORCEPROP 0 LAST PATH I71
J 0
(-475 2475);
DISPLAY 1.021277 (-475 2475);
DISPLAY INVISIBLE (-475 2475);
FORCEPROP 2 LAST CDS_LOCATION U22
J 0
(-475 2525);
DISPLAY 1.021277 (-475 2525);
DISPLAY INVISIBLE (-475 2525);
FORCEPROP 2 LAST $SEC 1
J 0
(-475 2525);
DISPLAY 0.680851 (-475 2525);
PAINT MONO (-475 2525);
DISPLAY INVISIBLE (-475 2525);
FORCEPROP 2 LAST CDS_SEC 1
J 0
(-475 2525);
DISPLAY 1.021277 (-475 2525);
DISPLAY INVISIBLE (-475 2525);
FORCEADD UNIVERSAL_POWER..1
(1250 2725);
FORCEPROP 3 LASTPIN (1250 2675) SIG_NAME PVNN_TERM_CPU0\g
J 0
(1260 2685);
DISPLAY 0.659574 (1260 2685);
PAINT MONO (1260 2685);
DISPLAY INVISIBLE (1260 2685);
FORCEPROP 1 LAST HDL_POWER PVNN_TERM_CPU0
J 1
(1250 2775);
DISPLAY 0.872340 (1250 2775);
PAINT GREEN (1250 2775);
FORCEPROP 2 LAST CDS_LIB logical_power
J 0
(1250 2725);
PAINT MONO (1250 2725);
DISPLAY INVISIBLE (1250 2725);
FORCEPROP 1 LAST PATH I72
J 0
(1300 2750);
DISPLAY 0.872340 (1300 2750);
PAINT AQUA (1300 2750);
DISPLAY INVISIBLE (1300 2750);
FORCEADD UNIVERSAL_POWER..1
(600 2725);
FORCEPROP 3 LASTPIN (600 2675) SIG_NAME PVNN_TERM_CPU1\g
J 0
(610 2685);
DISPLAY 0.659574 (610 2685);
PAINT MONO (610 2685);
DISPLAY INVISIBLE (610 2685);
FORCEPROP 1 LAST HDL_POWER PVNN_TERM_CPU1
J 1
(600 2775);
DISPLAY 0.872340 (600 2775);
PAINT GREEN (600 2775);
FORCEPROP 2 LAST CDS_LIB logical_power
J 0
(600 2725);
PAINT MONO (600 2725);
DISPLAY INVISIBLE (600 2725);
FORCEPROP 1 LAST PATH I73
J 0
(650 2750);
DISPLAY 0.872340 (650 2750);
PAINT AQUA (650 2750);
DISPLAY INVISIBLE (650 2750);
FORCEADD UNIVERSAL_POWER..1
(-1000 2675);
FORCEPROP 3 LASTPIN (-1000 2625) SIG_NAME P3V3_AUX\g
J 0
(-990 2635);
DISPLAY 0.659574 (-990 2635);
PAINT MONO (-990 2635);
DISPLAY INVISIBLE (-990 2635);
FORCEPROP 1 LAST HDL_POWER P3V3_AUX
J 1
(-1000 2725);
DISPLAY 0.872340 (-1000 2725);
PAINT GREEN (-1000 2725);
FORCEPROP 2 LAST CDS_LIB logical_power
J 0
(-1000 2675);
PAINT MONO (-1000 2675);
DISPLAY INVISIBLE (-1000 2675);
FORCEPROP 1 LAST PATH I74
J 0
(-950 2700);
DISPLAY 0.872340 (-950 2700);
PAINT AQUA (-950 2700);
DISPLAY INVISIBLE (-950 2700);
FORCEADD Q_RES..2
(1250 2250);
FORCEPROP 1 LAST PART_NUMBER CS07502FB04
J 0
(1290 2125);
DISPLAY 0.510638 (1290 2125);
DISPLAY INVISIBLE (1290 2125);
FORCEPROP 1 LAST TOLERANCE 1%
J 0
(1295 2275);
DISPLAY 0.510638 (1295 2275);
FORCEPROP 1 LAST MATERIAL CHIP
J 0
(1290 2175);
DISPLAY 0.510638 (1290 2175);
FORCEPROP 1 LAST WATTAGE 1/16W
J 0
(1290 2225);
DISPLAY 0.510638 (1290 2225);
FORCEPROP 1 LAST PACK_TYPE 0402LF
J 0
(1290 2075);
DISPLAY 0.510638 (1290 2075);
FORCEPROP 1 LAST VALUE 75
J 0
(1295 2325);
DISPLAY 0.510638 (1295 2325);
FORCEPROP 1 LAST $LOCATION R744
J 0
(1295 2375);
DISPLAY 0.978723 (1295 2375);
FORCEPROP 2 LAST CDS_LIB pure_quanta
J 0
(1250 2250);
PAINT MONO (1250 2250);
DISPLAY INVISIBLE (1250 2250);
FORCEPROP 1 LAST PATH I77
J 0
(1300 2425);
DISPLAY 0.978723 (1300 2425);
PAINT WHITE (1300 2425);
DISPLAY INVISIBLE (1300 2425);
FORCEPROP 2 LAST CDS_LOCATION R744
J 0
(1300 2475);
DISPLAY 1.021277 (1300 2475);
DISPLAY INVISIBLE (1300 2475);
FORCEPROP 2 LAST $SEC 1
J 0
(1300 2475);
DISPLAY 0.680851 (1300 2475);
PAINT MONO (1300 2475);
DISPLAY INVISIBLE (1300 2475);
FORCEPROP 2 LAST CDS_SEC 1
J 0
(1300 2475);
DISPLAY 1.021277 (1300 2475);
DISPLAY INVISIBLE (1300 2475);
FORCEPROP 1 LASTPIN (1250 2350) $PN 1
J 0
(1255 2312);
DISPLAY 0.787234 (1255 2312);
DISPLAY INVISIBLE (1255 2312);
FORCEPROP 1 LASTPIN (1250 2150) $PN 2
J 0
(1255 2160);
DISPLAY 0.787234 (1255 2160);
DISPLAY INVISIBLE (1255 2160);
FORCEADD Q_RES..2
(600 2250);
FORCEPROP 1 LAST PART_NUMBER CS07502FB04
J 0
(640 2125);
DISPLAY 0.510638 (640 2125);
DISPLAY INVISIBLE (640 2125);
FORCEPROP 1 LAST TOLERANCE 1%
J 0
(645 2275);
DISPLAY 0.510638 (645 2275);
FORCEPROP 1 LAST VALUE 75
J 0
(645 2325);
DISPLAY 0.510638 (645 2325);
FORCEPROP 1 LAST WATTAGE 1/16W
J 0
(640 2225);
DISPLAY 0.510638 (640 2225);
FORCEPROP 1 LAST MATERIAL CHIP
J 0
(640 2175);
DISPLAY 0.510638 (640 2175);
FORCEPROP 1 LAST PACK_TYPE 0402LF
J 0
(640 2075);
DISPLAY 0.510638 (640 2075);
FORCEPROP 1 LAST $LOCATION R742
J 0
(645 2375);
DISPLAY 0.978723 (645 2375);
FORCEPROP 1 LASTPIN (600 2350) $PN 1
J 0
(605 2312);
DISPLAY 0.787234 (605 2312);
FORCEPROP 1 LASTPIN (600 2150) $PN 2
J 0
(605 2160);
DISPLAY 0.787234 (605 2160);
FORCEPROP 2 LAST CDS_LIB pure_quanta
J 0
(600 2250);
PAINT MONO (600 2250);
DISPLAY INVISIBLE (600 2250);
FORCEPROP 1 LAST PATH I78
J 0
(650 2425);
DISPLAY 0.978723 (650 2425);
PAINT WHITE (650 2425);
DISPLAY INVISIBLE (650 2425);
FORCEPROP 2 LAST CDS_LOCATION R742
J 0
(650 2475);
DISPLAY 1.021277 (650 2475);
DISPLAY INVISIBLE (650 2475);
FORCEPROP 2 LAST $SEC 1
J 0
(650 2475);
DISPLAY 0.680851 (650 2475);
PAINT MONO (650 2475);
DISPLAY INVISIBLE (650 2475);
FORCEPROP 2 LAST CDS_SEC 1
J 0
(650 2475);
DISPLAY 1.021277 (650 2475);
DISPLAY INVISIBLE (650 2475);
FORCEADD UNIVERSAL_GND..1
(-175 1500);
FORCEPROP 3 LASTPIN (-175 1550) SIG_NAME GND\g
J 0
(-165 1560);
DISPLAY 0.659574 (-165 1560);
PAINT MONO (-165 1560);
DISPLAY INVISIBLE (-165 1560);
FORCEPROP 2 LAST CDS_LIB logical_power
J 0
(-175 1500);
PAINT MONO (-175 1500);
DISPLAY INVISIBLE (-175 1500);
FORCEPROP 1 LAST HDL_POWER GND
J 1
(-150 1425);
DISPLAY 0.872340 (-150 1425);
PAINT GREEN (-150 1425);
DISPLAY INVISIBLE (-150 1425);
FORCEPROP 1 LAST PATH I79
J 0
(-100 1500);
DISPLAY 0.872340 (-100 1500);
PAINT AQUA (-100 1500);
DISPLAY INVISIBLE (-100 1500);
FORCEADD Q_CAP..1
R 2
(-1150 2400);
FORCEPROP 1 LAST PART_NUMBER CH5104KEB02
J 2
(-1200 2250);
DISPLAY 0.510638 (-1200 2250);
DISPLAY INVISIBLE (-1200 2250);
FORCEPROP 1 LAST MATERIAL X6S
J 2
(-1200 2300);
DISPLAY 0.510638 (-1200 2300);
FORCEPROP 1 LAST TOLERANCE 10%
J 2
(-1200 2350);
DISPLAY 0.510638 (-1200 2350);
FORCEPROP 1 LAST VALUE 1UF
J 2
(-1200 2450);
DISPLAY 0.510638 (-1200 2450);
FORCEPROP 1 LAST PACK_TYPE C0402
J 2
(-1200 2200);
DISPLAY 0.510638 (-1200 2200);
FORCEPROP 1 LAST VOLTAGE 25V
J 2
(-1200 2400);
DISPLAY 0.510638 (-1200 2400);
FORCEPROP 1 LAST $LOCATION C542
J 2
(-1200 2500);
DISPLAY 0.978723 (-1200 2500);
FORCEPROP 1 LASTPIN (-1150 2500) $PN 1
J 2
(-1160 2480);
DISPLAY 0.787234 (-1160 2480);
FORCEPROP 1 LASTPIN (-1150 2300) $PN 2
J 2
(-1160 2280);
DISPLAY 0.787234 (-1160 2280);
FORCEPROP 2 LAST CDS_LIB pure_quanta
J 2
(-1150 2400);
PAINT MONO (-1150 2400);
DISPLAY INVISIBLE (-1150 2400);
FORCEPROP 1 LAST PATH I80
J 2
(-1200 2550);
DISPLAY 0.978723 (-1200 2550);
PAINT WHITE (-1200 2550);
DISPLAY INVISIBLE (-1200 2550);
FORCEPROP 2 LAST CDS_LOCATION C542
J 0
(-1200 2600);
DISPLAY 1.021277 (-1200 2600);
DISPLAY INVISIBLE (-1200 2600);
FORCEPROP 2 LAST $SEC 1
J 0
(-1200 2600);
DISPLAY 0.680851 (-1200 2600);
PAINT MONO (-1200 2600);
DISPLAY INVISIBLE (-1200 2600);
FORCEPROP 2 LAST CDS_SEC 1
J 0
(-1200 2600);
DISPLAY 1.021277 (-1200 2600);
DISPLAY INVISIBLE (-1200 2600);
FORCEADD Q_CAP..1
R 2
(-1500 2400);
FORCEPROP 1 LAST PART_NUMBER CH4104K1B00
J 2
(-1550 2250);
DISPLAY 0.510638 (-1550 2250);
DISPLAY INVISIBLE (-1550 2250);
FORCEPROP 1 LAST PACK_TYPE 0402
J 2
(-1550 2200);
DISPLAY 0.510638 (-1550 2200);
FORCEPROP 1 LAST VALUE 0.1UF
J 2
(-1550 2450);
DISPLAY 0.510638 (-1550 2450);
FORCEPROP 1 LAST VOLTAGE 25V
J 2
(-1550 2400);
DISPLAY 0.510638 (-1550 2400);
FORCEPROP 1 LAST TOLERANCE 10%
J 2
(-1550 2350);
DISPLAY 0.510638 (-1550 2350);
FORCEPROP 1 LAST MATERIAL X7R
J 2
(-1550 2300);
DISPLAY 0.510638 (-1550 2300);
FORCEPROP 1 LAST $LOCATION C540
J 2
(-1550 2500);
DISPLAY 0.978723 (-1550 2500);
FORCEPROP 1 LASTPIN (-1500 2500) $PN 1
J 2
(-1510 2480);
DISPLAY 0.787234 (-1510 2480);
FORCEPROP 1 LASTPIN (-1500 2300) $PN 2
J 2
(-1510 2280);
DISPLAY 0.787234 (-1510 2280);
FORCEPROP 2 LAST CDS_LIB pure_quanta
J 2
(-1500 2400);
PAINT MONO (-1500 2400);
DISPLAY INVISIBLE (-1500 2400);
FORCEPROP 1 LAST PATH I81
J 2
(-1550 2550);
DISPLAY 0.978723 (-1550 2550);
PAINT WHITE (-1550 2550);
DISPLAY INVISIBLE (-1550 2550);
FORCEPROP 2 LAST CDS_LOCATION C540
J 0
(-1550 2600);
DISPLAY 1.021277 (-1550 2600);
DISPLAY INVISIBLE (-1550 2600);
FORCEPROP 2 LAST $SEC 1
J 0
(-1550 2600);
DISPLAY 0.680851 (-1550 2600);
PAINT MONO (-1550 2600);
DISPLAY INVISIBLE (-1550 2600);
FORCEPROP 2 LAST CDS_SEC 1
J 0
(-1550 2600);
DISPLAY 1.021277 (-1550 2600);
DISPLAY INVISIBLE (-1550 2600);
FORCEADD UNIVERSAL_GND..1
(-1500 2100);
FORCEPROP 3 LASTPIN (-1500 2150) SIG_NAME GND\g
J 0
(-1490 2160);
DISPLAY 0.659574 (-1490 2160);
PAINT MONO (-1490 2160);
DISPLAY INVISIBLE (-1490 2160);
FORCEPROP 2 LAST CDS_LIB logical_power
J 0
(-1500 2100);
PAINT MONO (-1500 2100);
DISPLAY INVISIBLE (-1500 2100);
FORCEPROP 1 LAST HDL_POWER GND
J 1
(-1475 2025);
DISPLAY 0.872340 (-1475 2025);
PAINT GREEN (-1475 2025);
DISPLAY INVISIBLE (-1475 2025);
FORCEPROP 1 LAST PATH I82
J 0
(-1425 2100);
DISPLAY 0.872340 (-1425 2100);
PAINT AQUA (-1425 2100);
DISPLAY INVISIBLE (-1425 2100);
FORCEADD OFFPAGE..1
(-1850 2000);
FORCEPROP 2 LAST $XR0 133 
J 0
(-2102 2000);
DISPLAY 0.638298 (-2102 2000);
PAINT MONO (-2102 2000);
FORCEPROP 2 LAST CDS_LIB standard
J 0
(-1850 2000);
PAINT MONO (-1850 2000);
DISPLAY INVISIBLE (-1850 2000);
FORCEPROP 1 LAST OFFPAGE TRUE
J 0
(-1525 1875);
DISPLAY 0.872340 (-1525 1875);
PAINT GREEN (-1525 1875);
DISPLAY INVISIBLE (-1525 1875);
FORCEPROP 1 LAST COMMENT_BODY TRUE
J 0
(-1725 1900);
DISPLAY 0.872340 (-1725 1900);
PAINT GREEN (-1725 1900);
DISPLAY INVISIBLE (-1725 1900);
FORCEPROP 2 LAST PATH I84
J 0
(-1800 2075);
DISPLAY 1.021277 (-1800 2075);
DISPLAY INVISIBLE (-1800 2075);
FORCEADD OFFPAGE..2
R 2
(-1850 1900);
FORCEPROP 2 LAST $XR0 132 
J 0
(-2105 1900);
DISPLAY 0.638298 (-2105 1900);
PAINT MONO (-2105 1900);
FORCEPROP 2 LAST CDS_LIB standard
J 0
(-1850 1900);
PAINT MONO (-1850 1900);
DISPLAY INVISIBLE (-1850 1900);
FORCEPROP 1 LAST OFFPAGE TRUE
J 2
(-2175 1775);
DISPLAY 0.872340 (-2175 1775);
DISPLAY INVISIBLE (-2175 1775);
FORCEPROP 1 LAST COMMENT_BODY TRUE
J 2
(-1805 1805);
DISPLAY 0.872340 (-1805 1805);
PAINT GREEN (-1805 1805);
DISPLAY INVISIBLE (-1805 1805);
FORCEPROP 2 LAST PATH I85
J 0
(-1800 1975);
DISPLAY 1.021277 (-1800 1975);
DISPLAY INVISIBLE (-1800 1975);
FORCEADD OFFPAGE..4
(1625 2000);
FORCEPROP 2 LAST $XR1 133 
J 0
(1901 2000);
DISPLAY 0.638298 (1901 2000);
PAINT MONO (1901 2000);
FORCEPROP 2 LAST $XR0 13 
J 0
(1811 2000);
DISPLAY 0.638298 (1811 2000);
PAINT MONO (1811 2000);
FORCEPROP 2 LAST CDS_LIB standard
J 0
(1625 2000);
PAINT MONO (1625 2000);
DISPLAY INVISIBLE (1625 2000);
FORCEPROP 1 LAST OFFPAGE TRUE
J 0
(1950 1875);
DISPLAY 1.170213 (1950 1875);
PAINT GREEN (1950 1875);
DISPLAY INVISIBLE (1950 1875);
FORCEPROP 1 LAST COMMENT_BODY TRUE
J 0
(1600 1900);
DISPLAY 1.170213 (1600 1900);
PAINT GREEN (1600 1900);
DISPLAY INVISIBLE (1600 1900);
FORCEPROP 2 LAST PATH I86
J 0
(1800 2075);
DISPLAY 1.021277 (1800 2075);
DISPLAY INVISIBLE (1800 2075);
FORCEADD OFFPAGE..4
(1625 1900);
FORCEPROP 2 LAST $XR0 44 
J 0
(1811 1900);
DISPLAY 0.638298 (1811 1900);
PAINT MONO (1811 1900);
FORCEPROP 2 LAST CDS_LIB standard
J 0
(1625 1900);
PAINT MONO (1625 1900);
DISPLAY INVISIBLE (1625 1900);
FORCEPROP 1 LAST OFFPAGE TRUE
J 0
(1950 1775);
DISPLAY 1.170213 (1950 1775);
PAINT GREEN (1950 1775);
DISPLAY INVISIBLE (1950 1775);
FORCEPROP 1 LAST COMMENT_BODY TRUE
J 0
(1600 1800);
DISPLAY 1.170213 (1600 1800);
PAINT GREEN (1600 1800);
DISPLAY INVISIBLE (1600 1800);
FORCEPROP 2 LAST PATH I87
J 0
(1800 1975);
DISPLAY 1.021277 (1800 1975);
DISPLAY INVISIBLE (1800 1975);
FORCEADD OFFPAGE..4
(4675 350);
FORCEPROP 2 LAST $XR1 133 
J 0
(4951 350);
DISPLAY 0.638298 (4951 350);
PAINT MONO (4951 350);
FORCEPROP 2 LAST $XR0 13 
J 0
(4861 350);
DISPLAY 0.638298 (4861 350);
PAINT MONO (4861 350);
FORCEPROP 2 LAST CDS_LIB standard
J 0
(4675 350);
PAINT MONO (4675 350);
DISPLAY INVISIBLE (4675 350);
FORCEPROP 1 LAST OFFPAGE TRUE
J 0
(5000 225);
DISPLAY 1.170213 (5000 225);
PAINT GREEN (5000 225);
DISPLAY INVISIBLE (5000 225);
FORCEPROP 1 LAST COMMENT_BODY TRUE
J 0
(4650 250);
DISPLAY 1.170213 (4650 250);
PAINT GREEN (4650 250);
DISPLAY INVISIBLE (4650 250);
FORCEPROP 2 LAST PATH I90
J 0
(4850 425);
DISPLAY 1.021277 (4850 425);
DISPLAY INVISIBLE (4850 425);
FORCEADD OFFPAGE..2
(4675 250);
FORCEPROP 2 LAST $XR1 44 
J 0
(4984 250);
DISPLAY 0.638298 (4984 250);
PAINT MONO (4984 250);
FORCEPROP 2 LAST $XR0 133 
J 0
(4864 250);
DISPLAY 0.638298 (4864 250);
PAINT MONO (4864 250);
FORCEPROP 2 LAST CDS_LIB standard
J 0
(4675 250);
PAINT MONO (4675 250);
DISPLAY INVISIBLE (4675 250);
FORCEPROP 1 LAST OFFPAGE TRUE
J 0
(5000 125);
DISPLAY 0.872340 (5000 125);
PAINT GREEN (5000 125);
DISPLAY INVISIBLE (5000 125);
FORCEPROP 1 LAST COMMENT_BODY TRUE
J 0
(4630 155);
DISPLAY 0.872340 (4630 155);
PAINT GREEN (4630 155);
DISPLAY INVISIBLE (4630 155);
FORCEPROP 2 LAST PATH I91
J 0
(4850 325);
DISPLAY 1.021277 (4850 325);
DISPLAY INVISIBLE (4850 325);
FORCEADD UNIVERSAL_GND..1
(3800 0);
FORCEPROP 3 LASTPIN (3800 50) SIG_NAME GND\g
J 0
(3810 60);
DISPLAY 0.659574 (3810 60);
PAINT MONO (3810 60);
DISPLAY INVISIBLE (3810 60);
FORCEPROP 2 LAST CDS_LIB logical_power
J 0
(3800 0);
PAINT MONO (3800 0);
DISPLAY INVISIBLE (3800 0);
FORCEPROP 1 LAST HDL_POWER GND
J 1
(3825 -75);
DISPLAY 0.872340 (3825 -75);
PAINT GREEN (3825 -75);
DISPLAY INVISIBLE (3825 -75);
FORCEPROP 1 LAST PATH I92
J 0
(3875 0);
DISPLAY 0.872340 (3875 0);
PAINT AQUA (3875 0);
DISPLAY INVISIBLE (3875 0);
FORCEADD UNIVERSAL_POWER..1
(2900 925);
FORCEPROP 3 LASTPIN (2900 875) SIG_NAME P3V3_AUX\g
J 0
(2910 885);
DISPLAY 0.659574 (2910 885);
PAINT MONO (2910 885);
DISPLAY INVISIBLE (2910 885);
FORCEPROP 1 LAST HDL_POWER P3V3_AUX
J 1
(2900 975);
DISPLAY 0.872340 (2900 975);
PAINT GREEN (2900 975);
FORCEPROP 2 LAST CDS_LIB logical_power
J 0
(2900 925);
PAINT MONO (2900 925);
DISPLAY INVISIBLE (2900 925);
FORCEPROP 1 LAST PATH I93
J 0
(2950 950);
DISPLAY 0.872340 (2950 950);
PAINT AQUA (2950 950);
DISPLAY INVISIBLE (2950 950);
FORCEADD Q_CAP..1
R 2
(2750 650);
FORCEPROP 1 LAST PART_NUMBER CH4104K1B00
J 2
(2700 500);
DISPLAY 0.510638 (2700 500);
DISPLAY INVISIBLE (2700 500);
FORCEPROP 1 LAST VALUE 0.1UF
J 2
(2700 700);
DISPLAY 0.510638 (2700 700);
FORCEPROP 1 LAST TOLERANCE 10%
J 2
(2700 600);
DISPLAY 0.510638 (2700 600);
FORCEPROP 1 LAST VOLTAGE 25V
J 2
(2700 650);
DISPLAY 0.510638 (2700 650);
FORCEPROP 1 LAST MATERIAL X7R
J 2
(2700 550);
DISPLAY 0.510638 (2700 550);
FORCEPROP 1 LAST PACK_TYPE 0402
J 2
(2700 450);
DISPLAY 0.510638 (2700 450);
FORCEPROP 1 LAST $LOCATION C544
J 2
(2700 750);
DISPLAY 0.978723 (2700 750);
FORCEPROP 1 LASTPIN (2750 750) $PN 1
J 2
(2740 730);
DISPLAY 0.787234 (2740 730);
FORCEPROP 1 LASTPIN (2750 550) $PN 2
J 2
(2740 530);
DISPLAY 0.787234 (2740 530);
FORCEPROP 2 LAST CDS_LIB pure_quanta
J 0
(2750 650);
PAINT MONO (2750 650);
DISPLAY INVISIBLE (2750 650);
FORCEPROP 1 LAST PATH I94
J 2
(2700 800);
DISPLAY 0.978723 (2700 800);
PAINT WHITE (2700 800);
DISPLAY INVISIBLE (2700 800);
FORCEPROP 2 LAST CDS_LOCATION C544
J 0
(2700 850);
DISPLAY 1.021277 (2700 850);
DISPLAY INVISIBLE (2700 850);
FORCEPROP 2 LAST $SEC 1
J 0
(2700 850);
DISPLAY 0.680851 (2700 850);
PAINT MONO (2700 850);
DISPLAY INVISIBLE (2700 850);
FORCEPROP 2 LAST CDS_SEC 1
J 0
(2700 850);
DISPLAY 1.021277 (2700 850);
DISPLAY INVISIBLE (2700 850);
FORCEADD UNIVERSAL_GND..1
(2750 450);
FORCEPROP 3 LASTPIN (2750 500) SIG_NAME GND\g
J 0
(2760 510);
DISPLAY 0.659574 (2760 510);
PAINT MONO (2760 510);
DISPLAY INVISIBLE (2760 510);
FORCEPROP 2 LAST CDS_LIB logical_power
J 0
(2750 450);
PAINT MONO (2750 450);
DISPLAY INVISIBLE (2750 450);
FORCEPROP 1 LAST HDL_POWER GND
J 1
(2775 375);
DISPLAY 0.872340 (2775 375);
PAINT GREEN (2775 375);
DISPLAY INVISIBLE (2775 375);
FORCEPROP 1 LAST PATH I95
J 0
(2825 450);
DISPLAY 0.872340 (2825 450);
PAINT AQUA (2825 450);
DISPLAY INVISIBLE (2825 450);
FORCEADD 74LVC1G02GW..1
(900 200);
FORCEPROP 1 LAST PART_NUMBER ALVC1G02000
J 0
(1075 60);
DISPLAY 0.723404 (1075 60);
PAINT GREEN (1075 60);
DISPLAY INVISIBLE (1075 60);
FORCEPROP 2 LAST PACK_TYPE SMLF
J 0
(1000 375);
DISPLAY 0.808511 (1000 375);
FORCEPROP 2 LAST VALUE 74LVC1G02GW
J 0
(1000 325);
DISPLAY 0.808511 (1000 325);
FORCEPROP 1 LAST MATERIAL IC
J 0
(1075 10);
DISPLAY 0.723404 (1075 10);
PAINT GREEN (1075 10);
FORCEPROP 1 LAST $LOCATION U23
J 0
(1075 105);
DISPLAY 0.723404 (1075 105);
PAINT GREEN (1075 105);
FORCEPROP 2 LASTPIN (600 150) $PN 2
J 2
(590 160);
DISPLAY 0.808511 (590 160);
FORCEPROP 2 LASTPIN (600 250) $PN 1
J 2
(590 260);
DISPLAY 0.808511 (590 260);
FORCEPROP 2 LASTPIN (900 50) $PN 3
R 1
J 2
(890 40);
DISPLAY 0.808511 (890 40);
FORCEPROP 2 LASTPIN (900 350) $PN 5
R 1
J 0
(890 360);
DISPLAY 0.808511 (890 360);
FORCEPROP 2 LASTPIN (1200 200) $PN 4
J 0
(1210 210);
DISPLAY 0.808511 (1210 210);
FORCEPROP 2 LAST CDS_LIB pure_quanta
J 0
(900 200);
PAINT MONO (900 200);
DISPLAY INVISIBLE (900 200);
FORCEPROP 1 LAST NEEDS_NO_SIZE TRUE
J 0
(900 200);
DISPLAY 0.468085 (900 200);
PAINT GREEN (900 200);
DISPLAY INVISIBLE (900 200);
FORCEPROP 1 LAST PATH I96
J 0
(1300 55);
DISPLAY 0.723404 (1300 55);
PAINT GREEN (1300 55);
DISPLAY INVISIBLE (1300 55);
FORCEPROP 2 LAST CDS_LOCATION U23
J 0
(1000 425);
DISPLAY 1.021277 (1000 425);
DISPLAY INVISIBLE (1000 425);
FORCEPROP 2 LAST $SEC 1
J 0
(1000 425);
DISPLAY 0.680851 (1000 425);
PAINT MONO (1000 425);
DISPLAY INVISIBLE (1000 425);
FORCEPROP 2 LAST CDS_SEC 1
J 0
(1000 425);
DISPLAY 1.021277 (1000 425);
DISPLAY INVISIBLE (1000 425);
FORCEADD Q_RES..1
(2075 200);
FORCEPROP 1 LAST PART_NUMBER CS03322FB03
J 0
(1950 250);
DISPLAY 0.510638 (1950 250);
DISPLAY INVISIBLE (1950 250);
FORCEPROP 1 LAST MATERIAL CHIP
J 0
(1950 300);
DISPLAY 0.510638 (1950 300);
FORCEPROP 1 LAST PACK_TYPE 0402LF
J 0
(2400 200);
DISPLAY 0.638298 (2400 200);
FORCEPROP 1 LAST TOLERANCE 1%
J 0
(2325 200);
DISPLAY 0.638298 (2325 200);
FORCEPROP 1 LAST VALUE 33.2
J 2
(2300 200);
DISPLAY 0.638298 (2300 200);
FORCEPROP 1 LAST WATTAGE 1/16W
J 2
(2225 300);
DISPLAY 0.510638 (2225 300);
FORCEPROP 1 LAST $LOCATION R745
J 0
(1800 200);
DISPLAY 0.638298 (1800 200);
FORCEPROP 1 LASTPIN (1975 200) $PN 1
J 0
(1987 212);
DISPLAY 0.787234 (1987 212);
FORCEPROP 1 LASTPIN (2175 200) $PN 2
J 0
(2137 212);
DISPLAY 0.787234 (2137 212);
FORCEPROP 2 LAST CDS_LIB pure_quanta
J 0
(2075 200);
PAINT MONO (2075 200);
DISPLAY INVISIBLE (2075 200);
FORCEPROP 1 LAST PATH I97
J 0
(2025 350);
DISPLAY 0.978723 (2025 350);
PAINT WHITE (2025 350);
DISPLAY INVISIBLE (2025 350);
FORCEPROP 2 LAST CDS_LOCATION R745
J 0
(2025 400);
DISPLAY 1.021277 (2025 400);
DISPLAY INVISIBLE (2025 400);
FORCEPROP 2 LAST $SEC 1
J 0
(2025 400);
DISPLAY 0.680851 (2025 400);
PAINT MONO (2025 400);
DISPLAY INVISIBLE (2025 400);
FORCEPROP 2 LAST CDS_SEC 1
J 0
(2025 400);
DISPLAY 1.021277 (2025 400);
DISPLAY INVISIBLE (2025 400);
FORCEADD UNIVERSAL_POWER..1
(900 925);
FORCEPROP 3 LASTPIN (900 875) SIG_NAME P3V3_AUX\g
J 0
(910 885);
DISPLAY 0.659574 (910 885);
PAINT MONO (910 885);
DISPLAY INVISIBLE (910 885);
FORCEPROP 1 LAST HDL_POWER P3V3_AUX
J 1
(900 975);
DISPLAY 0.872340 (900 975);
PAINT GREEN (900 975);
FORCEPROP 2 LAST CDS_LIB logical_power
J 0
(900 925);
PAINT MONO (900 925);
DISPLAY INVISIBLE (900 925);
FORCEPROP 1 LAST PATH I98
J 0
(950 950);
DISPLAY 0.872340 (950 950);
PAINT AQUA (950 950);
DISPLAY INVISIBLE (950 950);
FORCEADD UNIVERSAL_GND..1
(750 450);
FORCEPROP 3 LASTPIN (750 500) SIG_NAME GND\g
J 0
(760 510);
DISPLAY 0.659574 (760 510);
PAINT MONO (760 510);
DISPLAY INVISIBLE (760 510);
FORCEPROP 2 LAST CDS_LIB logical_power
J 0
(750 450);
PAINT MONO (750 450);
DISPLAY INVISIBLE (750 450);
FORCEPROP 1 LAST HDL_POWER GND
J 1
(775 375);
DISPLAY 0.872340 (775 375);
PAINT GREEN (775 375);
DISPLAY INVISIBLE (775 375);
FORCEPROP 1 LAST PATH I99
J 0
(825 450);
DISPLAY 0.872340 (825 450);
PAINT AQUA (825 450);
DISPLAY INVISIBLE (825 450);
FORCEADD QUANTA_TITLE_BLOCK_C..1
(5825 -1600);
FORCEPROP 0 LAST CDS_CON_LAST_MODIFIED Fri Aug 25 14:01:54 2023
J 0
(3940 -1585);
PAINT MONO (3940 -1585);
DISPLAY INVISIBLE (3940 -1585);
FORCEPROP 2 LAST CUSTOM_TXT_CDS <XR_PAGE_TITLE>
J 0
(-2065 3650);
DISPLAY 0.638298 (-2065 3650);
PAINT PINK (-2065 3650);
DISPLAY INVISIBLE (-2065 3650);
FORCEPROP 2 LAST CUSTOM_TXT_CDS <CON_LAST_MODIFIED>
J 0
(3940 -1585);
DISPLAY 0.978723 (3940 -1585);
FORCEPROP 2 LAST CUSTOM_TXT_CDS <NAME_1>
J 0
(2700 -1425);
FORCEPROP 2 LAST CUSTOM_TXT_CDS <NAME_2>
J 0
(2725 -1550);
FORCEPROP 2 LAST CUSTOM_TXT_CDS <Q_PROJ>
J 0
(3525 -1475);
DISPLAY 1.212766 (3525 -1475);
FORCEPROP 2 LAST CUSTOM_TXT_CDS <Q_REV>
J 0
(5641 -1497);
DISPLAY 1.212766 (5641 -1497);
FORCEPROP 2 LAST CUSTOM_TXT_CDS <CON_PAGE_NUM> OF <CON_TOTAL_PAGES>
J 0
(5375 -1600);
DISPLAY 0.978723 (5375 -1600);
FORCEPROP 2 LAST CUSTOM_TXT_CDS <Q_NUMBER>
J 0
(4422 -1497);
DISPLAY 1.212766 (4422 -1497);
FORCEPROP 1 LAST Q_TITLE SPR & PCH - DEBUG PORT (3/3)
J 0
(-3441 -1599);
DISPLAY 2.446809 (-3441 -1599);
PAINT GREEN (-3441 -1599);
FORCEPROP 1 LAST Q_DEPT 
J 1
(2062 -1551);
DISPLAY 1.957447 (2062 -1551);
PAINT GREEN (2062 -1551);
FORCEPROP 2 LAST CDS_XR_PAGE_TITLE CR-133 : @S9S_MB_2U_LIB.S9S_MB_2U(SCH_1):PAGE133
J 0
(-2065 3650);
DISPLAY 0.638298 (-2065 3650);
PAINT PINK (-2065 3650);
DISPLAY INVISIBLE (-2065 3650);
FORCEPROP 1 LAST COMMENT_BODY TRUE
J 0
(5837 -1613);
DISPLAY 0.978723 (5837 -1613);
PAINT GREEN (5837 -1613);
DISPLAY INVISIBLE (5837 -1613);
FORCEPROP 2 LAST PAGE_BORDER TRUE
J 0
(-2065 3650);
DISPLAY 0.638298 (-2065 3650);
PAINT PINK (-2065 3650);
DISPLAY INVISIBLE (-2065 3650);
FORCEPROP 1 LAST CDS_LMAN_SYM_OUTLINE -9475,6775,100,-125
J 0
(5825 -1600);
DISPLAY 0.468085 (5825 -1600);
PAINT GREEN (5825 -1600);
DISPLAY INVISIBLE (5825 -1600);
FORCEPROP 2 LAST CDS_LIB pure_quanta
J 0
(5825 -1600);
PAINT MONO (5825 -1600);
DISPLAY INVISIBLE (5825 -1600);
WIRE 16 -1 (-300 800)(-300 700);
WIRE 16 -1 (-1000 4175)(-1000 4125);
WIRE 16 -1 (600 3900)(600 4225);
WIRE 16 -1 (1250 4225)(1250 3900);
WIRE 16 -1 (1250 2675)(1250 2350);
WIRE 16 -1 (600 2350)(600 2675);
WIRE 16 -1 (-1000 2625)(-1000 2575);
WIRE 16 -1 (2900 875)(2900 825);
WIRE 16 -1 (900 875)(900 825);
WIRE 16 -1 (900 -150)(900 50);
WIRE 16 -1 (-175 3100)(-175 3500);
WIRE 16 -1 (-1500 3725)(-1500 3700);
WIRE 16 -1 (-1500 3725)(-1150 3725);
WIRE 16 -1 (-1500 3850)(-1500 3725);
WIRE 16 -1 (-175 1550)(-175 1950);
WIRE 16 -1 (-1500 2175)(-1500 2150);
WIRE 16 -1 (-1500 2175)(-1150 2175);
WIRE 16 -1 (-1500 2300)(-1500 2175);
WIRE 16 -1 (3800 50)(3800 150);
WIRE 16 -1 (2750 550)(2750 500);
WIRE 16 -1 (750 550)(750 500);
WIRE 16 -1 (3075 200)(2175 200);
FORCEPROP 0 LAST CDS_PHYS_NET_NAME TRC_PCH_PTI1_CLK
J 0
(2365 248);
PAINT MONO (2365 248);
DISPLAY INVISIBLE (2365 248);
FORCEPROP 2 LAST SIG_NAME FM_CPU_EN_R
J 0
(2615 210);
DISPLAY 0.638298 (2615 210);
PAINT WHITE (2615 210);
WIRE 16 -1 (-50 700)(-50 600);
WIRE 16 -1 (-300 700)(-50 700);
WIRE 16 -1 (-300 600)(-300 700);
WIRE 16 -1 (-175 3500)(-300 3500);
WIRE 16 -1 (-1500 4050)(-1500 4125);
WIRE 16 -1 (-1150 4050)(-1150 4125);
WIRE 16 -1 (-1500 4125)(-1150 4125);
WIRE 16 -1 (-1000 4125)(-1150 4125);
WIRE 16 -1 (-1000 3500)(-900 3500);
WIRE 16 -1 (-1000 3500)(-1000 4125);
WIRE 16 -1 (-1150 3850)(-1150 3725);
WIRE 16 -1 (-1500 2500)(-1500 2575);
WIRE 16 -1 (-1150 2500)(-1150 2575);
WIRE 16 -1 (-1500 2575)(-1150 2575);
WIRE 16 -1 (-1000 2575)(-1150 2575);
WIRE 16 -1 (-1000 1950)(-900 1950);
WIRE 16 -1 (-1000 1950)(-1000 2575);
WIRE 16 -1 (-175 1950)(-300 1950);
WIRE 16 -1 (-1150 2300)(-1150 2175);
WIRE 16 -1 (3800 150)(3675 150);
WIRE 16 -1 (2750 750)(2750 825);
WIRE 16 -1 (2900 825)(2750 825);
WIRE 16 -1 (2900 350)(2900 825);
WIRE 16 -1 (2900 350)(3075 350);
WIRE 16 -1 (750 750)(750 825);
WIRE 16 -1 (900 825)(750 825);
WIRE 16 -1 (900 350)(900 825);
WIRE 16 -1 (3675 350)(4625 350);
FORCEPROP 0 LAST CDS_PHYS_NET_NAME JTAG_DBP_CPU_QS_GTL_TMS
J 0
(3865 398);
PAINT MONO (3865 398);
DISPLAY INVISIBLE (3865 398);
FORCEPROP 2 LAST SIG_NAME JTAG_CPU0_MUX_GTL_TDO
J 0
(3865 360);
DISPLAY 0.638298 (3865 360);
PAINT WHITE (3865 360);
WIRE 16 -1 (3675 250)(4625 250);
FORCEPROP 0 LAST CDS_PHYS_NET_NAME JTAG_DBP_CPU_QS_GTL_TMS
J 0
(3865 298);
PAINT MONO (3865 298);
DISPLAY INVISIBLE (3865 298);
FORCEPROP 2 LAST SIG_NAME JTAG_MUX_CPU1_GTL_TDI
J 0
(3865 260);
DISPLAY 0.638298 (3865 260);
PAINT WHITE (3865 260);
WIRE 16 -1 (1975 200)(1200 200);
FORCEPROP 0 LAST CDS_PHYS_NET_NAME TRC_PCH_PTI1_CLK
J 0
(1390 248);
PAINT MONO (1390 248);
DISPLAY INVISIBLE (1390 248);
FORCEPROP 2 LAST SIG_NAME FM_CPU_EN
J 0
(1365 210);
DISPLAY 0.638298 (1365 210);
PAINT WHITE (1365 210);
WIRE 16 -1 (1575 1900)(600 1900);
WIRE 16 -1 (600 2150)(600 1900);
WIRE 16 -1 (-300 1900)(600 1900);
FORCEPROP 0 LAST CDS_PHYS_NET_NAME JTAG_DBP_CPU_QS_GTL_TMS
J 0
(-110 1948);
PAINT MONO (-110 1948);
DISPLAY INVISIBLE (-110 1948);
FORCEPROP 2 LAST SIG_NAME JTAG_CPU1_MUX_GTL_TDO
J 0
(-110 1910);
DISPLAY 0.638298 (-110 1910);
PAINT WHITE (-110 1910);
WIRE 16 -1 (1575 2000)(1250 2000);
WIRE 16 -1 (1250 2150)(1250 2000);
WIRE 16 -1 (-300 2000)(1250 2000);
FORCEPROP 0 LAST CDS_PHYS_NET_NAME JTAG_DBP_CPU_QS_GTL_TMS
J 0
(-110 2048);
PAINT MONO (-110 2048);
DISPLAY INVISIBLE (-110 2048);
FORCEPROP 2 LAST SIG_NAME JTAG_CPU0_MUX_GTL_TDO
J 0
(-110 2010);
DISPLAY 0.638298 (-110 2010);
PAINT WHITE (-110 2010);
WIRE 16 -1 (600 3700)(600 3450);
WIRE 16 -1 (1575 3450)(600 3450);
WIRE 16 -1 (-300 3450)(600 3450);
FORCEPROP 0 LAST CDS_PHYS_NET_NAME JTAG_DBP_CPU_QS_GTL_TMS
J 0
(-110 3498);
PAINT MONO (-110 3498);
DISPLAY INVISIBLE (-110 3498);
FORCEPROP 2 LAST SIG_NAME JTAG_MUX_CPU0_GTL_TDI
J 0
(-110 3460);
DISPLAY 0.638298 (-110 3460);
PAINT WHITE (-110 3460);
WIRE 16 -1 (1250 3700)(1250 3550);
WIRE 16 -1 (1575 3550)(1250 3550);
WIRE 16 -1 (-300 3550)(1250 3550);
FORCEPROP 0 LAST CDS_PHYS_NET_NAME JTAG_DBP_CPU_QS_GTL_TMS
J 0
(-110 3598);
PAINT MONO (-110 3598);
DISPLAY INVISIBLE (-110 3598);
FORCEPROP 2 LAST SIG_NAME JTAG_MUX_CPU1_GTL_TDI
J 0
(-110 3560);
DISPLAY 0.638298 (-110 3560);
PAINT WHITE (-110 3560);
WIRE 16 -1 (-650 250)(-300 250);
WIRE 16 -1 (-300 400)(-300 250);
WIRE 16 -1 (-200 250)(-300 250);
FORCEPROP 0 LAST CDS_PHYS_NET_NAME TRC_PCH_PTI1_CLK
J 0
(-260 298);
PAINT MONO (-260 298);
DISPLAY INVISIBLE (-260 298);
WIRE 16 -1 (600 250)(-200 250);
FORCEPROP 2 LAST SIG_NAME FM_CPU1_SKTOCC_N
J 0
(40 260);
DISPLAY 0.638298 (40 260);
PAINT WHITE (40 260);
WIRE 16 -1 (-200 0)(-200 250);
WIRE 16 -1 (-300 0)(-200 0);
WIRE 16 -1 (-50 400)(-50 150);
WIRE 16 -1 (600 150)(-50 150);
FORCEPROP 2 LAST SIG_NAME FM_CPU0_SKTOCC_N
J 0
(40 160);
DISPLAY 0.638298 (40 160);
PAINT WHITE (40 160);
WIRE 16 -1 (-150 150)(-650 150);
FORCEPROP 0 LAST CDS_PHYS_NET_NAME TRC_PCH_PTI1_CLK
J 0
(-260 198);
PAINT MONO (-260 198);
DISPLAY INVISIBLE (-260 198);
WIRE 16 -1 (-50 150)(-150 150);
WIRE 16 -1 (-150 -100)(-150 150);
WIRE 16 -1 (-300 -100)(-150 -100);
WIRE 16 -1 (-850 150)(-1825 150);
FORCEPROP 0 LAST CDS_PHYS_NET_NAME TRC_PCH_PTI1_CLK
J 0
(-1785 198);
PAINT MONO (-1785 198);
DISPLAY INVISIBLE (-1785 198);
FORCEPROP 2 LAST SIG_NAME FM_CPU0_SKTOCC_LVT3_N
J 0
(-1735 160);
DISPLAY 0.638298 (-1735 160);
PAINT WHITE (-1735 160);
WIRE 16 -1 (-850 250)(-1825 250);
FORCEPROP 0 LAST CDS_PHYS_NET_NAME TRC_PCH_PTI1_CLK
J 0
(-1785 298);
PAINT MONO (-1785 298);
DISPLAY INVISIBLE (-1785 298);
FORCEPROP 2 LAST SIG_NAME FM_CPU1_SKTOCC_LVT3_N
J 0
(-1735 260);
DISPLAY 0.638298 (-1735 260);
PAINT WHITE (-1735 260);
WIRE 16 -1 (-900 1900)(-1800 1900);
FORCEPROP 0 LAST CDS_PHYS_NET_NAME TRC_PCH_PTI1_CLK
J 0
(-1610 1948);
PAINT MONO (-1610 1948);
DISPLAY INVISIBLE (-1610 1948);
FORCEPROP 2 LAST SIG_NAME JTAG_MUX_QS_GTL_TDO
J 0
(-1660 1910);
DISPLAY 0.638298 (-1660 1910);
PAINT WHITE (-1660 1910);
WIRE 16 -1 (-900 2000)(-1800 2000);
FORCEPROP 0 LAST CDS_PHYS_NET_NAME TRC_PCH_PTI1_CLK
J 0
(-1610 2048);
PAINT MONO (-1610 2048);
DISPLAY INVISIBLE (-1610 2048);
FORCEPROP 2 LAST SIG_NAME FM_CPU1_SKTOCC_N
J 0
(-1660 2010);
DISPLAY 0.638298 (-1660 2010);
PAINT WHITE (-1660 2010);
WIRE 16 -1 (-900 3450)(-1800 3450);
FORCEPROP 0 LAST CDS_PHYS_NET_NAME TRC_PCH_PTI1_CLK
J 0
(-1610 3498);
PAINT MONO (-1610 3498);
DISPLAY INVISIBLE (-1610 3498);
FORCEPROP 2 LAST SIG_NAME JTAG_QS_MUX_GTL_TDI
J 0
(-1660 3460);
DISPLAY 0.638298 (-1660 3460);
PAINT WHITE (-1660 3460);
WIRE 16 -1 (-900 3550)(-1800 3550);
FORCEPROP 0 LAST CDS_PHYS_NET_NAME TRC_PCH_PTI1_CLK
J 0
(-1610 3598);
PAINT MONO (-1610 3598);
DISPLAY INVISIBLE (-1610 3598);
FORCEPROP 2 LAST SIG_NAME FM_CPU0_SKTOCC_N
J 0
(-1660 3560);
DISPLAY 0.638298 (-1660 3560);
PAINT WHITE (-1660 3560);
DOT 1 (-200 250);
DOT 1 (-150 150);
DOT 1 (-50 150);
DOT 1 (1250 2000);
DOT 1 (-1500 2175);
DOT 1 (-1150 2575);
DOT 1 (-1500 3725);
DOT 1 (-1150 4125);
DOT 1 (-1000 4125);
DOT 1 (600 3450);
DOT 1 (1250 3550);
DOT 1 (-300 250);
DOT 1 (-300 700);
DOT 1 (900 825);
DOT 1 (2900 825);
DOT 1 (-1000 2575);
DOT 1 (600 1900);
QUIT
